# T6G (Grand Teton) — schematic netlist excerpt (pin names and nets, part order shuffled) for the footprints in the layout excerpt that follows; sources: Cadence DE-HDL packaged netlist, KiCad conversion of 04192023_DAF0TMB3IC0_F0TG_MB_C_brd_V02_OCP.brd

R4074  Q_RES  10K 1% CHIP  pkg 0402LF  page 146 : A = P12V_AUX ; B = P12V_E1S_0_EN_G
R689  Q_RES  33.2 1% CHIP  pkg 0201LF  page 333 : A = SMB_RT_CPU1_P1_ROM_R_SCL ; B = SMB_RT_CPU1_P1_ROM_SCL
R971  Q_RES  10K 1% CHIP  pkg 0201LF  page 276 : A = RST_RT_CPU0_P0_RESET_R_N ; B = GND

(kicad_pcb
	(version 20260206)
	(generator "pcbnew")
	(generator_version "10.0")
	(general
		(thickness 1.6)
		(legacy_teardrops no)
	)
	(paper "A4")
	(title_block
		(title "04192023_DAF0TMB3IC0_F0TG_MB_C_brd_V02_OCP.brd")
		(comment 1 "Grand Teton / footprints 4431-4433 of 8354")
	)
	(layers
		(0 "F.Cu" signal "TOP")
		(4 "In1.Cu" signal "GND")
		(6 "In2.Cu" signal "IN1")
		(8 "In3.Cu" signal "GND1")
		(10 "In4.Cu" signal "IN2")
		(12 "In5.Cu" signal "GND2")
		(14 "In6.Cu" signal "IN3")
		(16 "In7.Cu" signal "GND3")
		(18 "In8.Cu" signal "VCC")
		(20 "In9.Cu" signal "VCC1")
		(22 "In10.Cu" signal "GND4")
		(24 "In11.Cu" signal "IN4")
		(26 "In12.Cu" signal "GND5")
		(28 "In13.Cu" signal "IN5")
		(30 "In14.Cu" signal "GND6")
		(32 "In15.Cu" signal "IN6")
		(34 "In16.Cu" signal "GND7")
		(2 "B.Cu" signal "BOTTOM")
		(9 "F.Adhes" user "F.Adhesive")
		(11 "B.Adhes" user "B.Adhesive")
		(13 "F.Paste" user "Package Geometry/Pastemask Top")
		(15 "B.Paste" user "Package Geometry/Pastemask Bottom")
		(5 "F.SilkS" user "Ref Des/Silkscreen Top")
		(7 "B.SilkS" user "Ref Des/Silkscreen Bottom")
		(1 "F.Mask" user "Board Geometry/Soldermask Top")
		(3 "B.Mask" user "Board Geometry/Soldermask Bottom")
		(17 "Dwgs.User" user "User.Drawings")
		(19 "Cmts.User" user "User.Comments")
		(21 "Eco1.User" user "User.Eco1")
		(23 "Eco2.User" user "User.Eco2")
		(25 "Edge.Cuts" user "Board Geometry/Outline")
		(27 "Margin" user)
		(31 "F.CrtYd" user "Package Geometry/Place Bound Top")
		(29 "B.CrtYd" user "Package Geometry/Place Bound Bottom")
		(35 "F.Fab" user "Ref Des/Assembly Top")
		(33 "B.Fab" user "Ref Des/Assembly Bottom")
	)
	(footprint ""
		(layer "F.Cu")
		(at 297.554142 -397.4084)
		(property "Reference" "R971"
			(at 0 0 0)
			(layer "F.SilkS")
			(hide yes)
			(effects
				(font
					(size 1.27 1.27)
				)
			)
		)
		(property "Value" ""
			(at 0 0 0)
			(layer "F.Fab")
			(effects
				(font
					(size 1.27 1.27)
				)
			)
		)
		(duplicate_pad_numbers_are_jumpers no)
		(fp_line
			(start -0.32512 -0.175006)
			(end 0.32512 -0.175006)
			(stroke
				(width 0.1)
				(type default)
			)
			(layer "F.Fab")
		)
		(fp_line
			(start -0.32512 0.175006)
			(end -0.32512 -0.175006)
			(stroke
				(width 0.1)
				(type default)
			)
			(layer "F.Fab")
		)
		(fp_line
			(start 0.32512 -0.175006)
			(end 0.32512 0.175006)
			(stroke
				(width 0.1)
				(type default)
			)
			(layer "F.Fab")
		)
		(fp_line
			(start 0.32512 0.175006)
			(end -0.32512 0.175006)
			(stroke
				(width 0.1)
				(type default)
			)
			(layer "F.Fab")
		)
		(pad "1" smd rect
			(at -0.2667 0)
			(size 0.3048 0.381)
			(layers "F.Cu" "F.Mask" "F.Paste")
			(net "RST_RT_CPU0_P0_RESET_R_N")
		)
		(pad "2" smd rect
			(at 0.2667 0 180)
			(size 0.3048 0.381)
			(layers "F.Cu" "F.Mask" "F.Paste")
			(net "GND")
		)
	)
	(footprint ""
		(layer "F.Cu")
		(at 257.766312 -66.86931 90)
		(property "Reference" "R4074"
			(at 0 0 90)
			(layer "F.SilkS")
			(hide yes)
			(effects
				(font
					(size 1.27 1.27)
				)
			)
		)
		(property "Value" ""
			(at 0 0 90)
			(layer "F.Fab")
			(effects
				(font
					(size 1.27 1.27)
				)
			)
		)
		(duplicate_pad_numbers_are_jumpers no)
		(fp_line
			(start 0.7874 -0.4064)
			(end 0.7874 0.4064)
			(stroke
				(width 0.1524)
				(type default)
			)
			(layer "F.SilkS")
		)
		(fp_line
			(start -0.7874 -0.4064)
			(end 0.7874 -0.4064)
			(stroke
				(width 0.1524)
				(type default)
			)
			(layer "F.SilkS")
		)
		(fp_line
			(start 0.7874 0.4064)
			(end -0.7874 0.4064)
			(stroke
				(width 0.1524)
				(type default)
			)
			(layer "F.SilkS")
		)
		(fp_line
			(start -0.7874 0.4064)
			(end -0.7874 -0.4064)
			(stroke
				(width 0.1524)
				(type default)
			)
			(layer "F.SilkS")
		)
		(fp_line
			(start -0.12065 -0.305054)
			(end -0.12065 -0.2794)
			(stroke
				(width 0.1)
				(type default)
			)
			(layer "F.Fab")
		)
		(fp_line
			(start -0.67945 -0.305054)
			(end -0.12065 -0.305054)
			(stroke
				(width 0.1)
				(type default)
			)
			(layer "F.Fab")
		)
		(fp_line
			(start 0.67945 -0.3048)
			(end 0.67945 0.3048)
			(stroke
				(width 0.1)
				(type default)
			)
			(layer "F.Fab")
		)
		(fp_line
			(start 0.12065 -0.3048)
			(end 0.67945 -0.3048)
			(stroke
				(width 0.1)
				(type default)
			)
			(layer "F.Fab")
		)
		(fp_line
			(start 0.12065 -0.2794)
			(end 0.12065 -0.3048)
			(stroke
				(width 0.1)
				(type default)
			)
			(layer "F.Fab")
		)
		(fp_line
			(start -0.12065 -0.2794)
			(end 0.12065 -0.2794)
			(stroke
				(width 0.1)
				(type default)
			)
			(layer "F.Fab")
		)
		(fp_line
			(start 0.120396 0.2794)
			(end -0.12065 0.2794)
			(stroke
				(width 0.1)
				(type default)
			)
			(layer "F.Fab")
		)
		(fp_line
			(start -0.12065 0.2794)
			(end -0.12065 0.3048)
			(stroke
				(width 0.1)
				(type default)
			)
			(layer "F.Fab")
		)
		(fp_line
			(start 0.67945 0.3048)
			(end 0.120396 0.3048)
			(stroke
				(width 0.1)
				(type default)
			)
			(layer "F.Fab")
		)
		(fp_line
			(start 0.120396 0.3048)
			(end 0.120396 0.2794)
			(stroke
				(width 0.1)
				(type default)
			)
			(layer "F.Fab")
		)
		(fp_line
			(start -0.12065 0.3048)
			(end -0.67945 0.3048)
			(stroke
				(width 0.1)
				(type default)
			)
			(layer "F.Fab")
		)
		(fp_line
			(start -0.67945 0.3048)
			(end -0.67945 -0.305054)
			(stroke
				(width 0.1)
				(type default)
			)
			(layer "F.Fab")
		)
		(pad "1" smd circle
			(at -0.40005 0 90)
			(size 0 0)
			(layers "F.Cu" "F.Mask" "F.Paste")
			(net "P12V_AUX")
		)
		(pad "2" smd circle
			(at 0.40005 0 90)
			(size 0 0)
			(layers "F.Cu" "F.Mask" "F.Paste")
			(net "P12V_E1S_0_EN_G")
		)
	)
	(footprint ""
		(layer "F.Cu")
		(at 109.22 -397.03248 90)
		(property "Reference" "R689"
			(at 0 0 90)
			(layer "F.SilkS")
			(hide yes)
			(effects
				(font
					(size 1.27 1.27)
				)
			)
		)
		(property "Value" ""
			(at 0 0 90)
			(layer "F.Fab")
			(effects
				(font
					(size 1.27 1.27)
				)
			)
		)
		(duplicate_pad_numbers_are_jumpers no)
		(fp_line
			(start 0.32512 -0.175006)
			(end 0.32512 0.175006)
			(stroke
				(width 0.1)
				(type default)
			)
			(layer "F.Fab")
		)
		(fp_line
			(start -0.32512 -0.175006)
			(end 0.32512 -0.175006)
			(stroke
				(width 0.1)
				(type default)
			)
			(layer "F.Fab")
		)
		(fp_line
			(start 0.32512 0.175006)
			(end -0.32512 0.175006)
			(stroke
				(width 0.1)
				(type default)
			)
			(layer "F.Fab")
		)
		(fp_line
			(start -0.32512 0.175006)
			(end -0.32512 -0.175006)
			(stroke
				(width 0.1)
				(type default)
			)
			(layer "F.Fab")
		)
		(pad "1" smd rect
			(at -0.2667 0 90)
			(size 0.3048 0.381)
			(layers "F.Cu" "F.Mask" "F.Paste")
			(net "SMB_RT_CPU1_P1_ROM_R_SCL")
		)
		(pad "2" smd rect
			(at 0.2667 0 270)
			(size 0.3048 0.381)
			(layers "F.Cu" "F.Mask" "F.Paste")
			(net "SMB_RT_CPU1_P1_ROM_SCL")
		)
	)
)
